# SCM (Grand Teton) — schematic netlist excerpt (pin names and nets, part order shuffled) for the footprints in the layout excerpt that follows; sources: Cadence DE-HDL packaged netlist, KiCad conversion of 12092022_DA0F0TMDCD0_F0T_Management_Board_D_brd_V3_OCP.brd

SW7  SW_PUSHBUTTON4P_12_G34_H2  SW4S_DTSAM-63N/K-S-Q-T/R MECH  pkg SW4S_DTSAM63N  page 50
  \1\  = GND
  \2\  = REAR_ID_RST_BTN_N
  \3\  = GND
  \4\  = GND

(kicad_pcb
	(version 20260206)
	(generator "pcbnew")
	(generator_version "10.0")
	(general
		(thickness 1.6)
		(legacy_teardrops no)
	)
	(paper "A4")
	(title_block
		(title "12092022_DA0F0TMDCD0_F0T_Management_Board_D_brd_V3_OCP.brd")
		(comment 1 "Grand Teton / footprints 615-615 of 1440")
	)
	(layers
		(0 "F.Cu" signal "TOP")
		(4 "In1.Cu" signal "GND")
		(6 "In2.Cu" signal "IN1")
		(8 "In3.Cu" signal "GND1")
		(10 "In4.Cu" signal "IN2")
		(12 "In5.Cu" signal "VCC")
		(14 "In6.Cu" signal "VCC1")
		(16 "In7.Cu" signal "IN3")
		(18 "In8.Cu" signal "GND2")
		(20 "In9.Cu" signal "IN4")
		(22 "In10.Cu" signal "GND3")
		(2 "B.Cu" signal "BOTTOM")
		(9 "F.Adhes" user "F.Adhesive")
		(11 "B.Adhes" user "B.Adhesive")
		(13 "F.Paste" user "Package Geometry/Pastemask Top")
		(15 "B.Paste" user "Package Geometry/Pastemask Bottom")
		(5 "F.SilkS" user "Ref Des/Silkscreen Top")
		(7 "B.SilkS" user "Ref Des/Silkscreen Bottom")
		(1 "F.Mask" user "Board Geometry/Soldermask Top")
		(3 "B.Mask" user "Board Geometry/Soldermask Bottom")
		(17 "Dwgs.User" user "User.Drawings")
		(19 "Cmts.User" user "User.Comments")
		(21 "Eco1.User" user "User.Eco1")
		(23 "Eco2.User" user "User.Eco2")
		(25 "Edge.Cuts" user "Board Geometry/Outline")
		(27 "Margin" user)
		(31 "F.CrtYd" user "Package Geometry/Place Bound Top")
		(29 "B.CrtYd" user "Package Geometry/Place Bound Bottom")
		(35 "F.Fab" user "Ref Des/Assembly Top")
		(33 "B.Fab" user "Ref Des/Assembly Bottom")
	)
	(footprint ""
		(layer "F.Cu")
		(at 82.00009 -2.94005)
		(property "Reference" "SW7"
			(at -5.2705 -5.448554 0)
			(unlocked yes)
			(layer "F.SilkS")
			(effects
				(font
					(size 0.7874 0.5842)
					(thickness 0.1524)
				)
				(justify left)
			)
		)
		(property "Value" ""
			(at 0 0 0)
			(layer "F.Fab")
			(effects
				(font
					(size 1.27 1.27)
				)
			)
		)
		(duplicate_pad_numbers_are_jumpers no)
		(fp_line
			(start -3.700018 -4.549902)
			(end -3.700018 -2.51206)
			(stroke
				(width 0.1524)
				(type default)
			)
			(layer "F.SilkS")
		)
		(fp_line
			(start -3.700018 -0.98806)
			(end -3.700018 -0.88646)
			(stroke
				(width 0.1524)
				(type default)
			)
			(layer "F.SilkS")
		)
		(fp_line
			(start -3.700018 1.39954)
			(end -3.700018 1.549908)
			(stroke
				(width 0.1524)
				(type default)
			)
			(layer "F.SilkS")
		)
		(fp_line
			(start -3.700018 1.549908)
			(end -1.75006 1.549908)
			(stroke
				(width 0.1524)
				(type default)
			)
			(layer "F.SilkS")
		)
		(fp_line
			(start -3.1496 -4.549902)
			(end -3.700018 -4.549902)
			(stroke
				(width 0.1524)
				(type default)
			)
			(layer "F.SilkS")
		)
		(fp_line
			(start -1.75006 1.549908)
			(end -1.75006 4.549902)
			(stroke
				(width 0.1524)
				(type default)
			)
			(layer "F.SilkS")
		)
		(fp_line
			(start -1.75006 4.549902)
			(end 1.75006 4.549902)
			(stroke
				(width 0.1524)
				(type default)
			)
			(layer "F.SilkS")
		)
		(fp_line
			(start 1.3716 -4.549902)
			(end -1.3716 -4.549902)
			(stroke
				(width 0.1524)
				(type default)
			)
			(layer "F.SilkS")
		)
		(fp_line
			(start 1.75006 1.549908)
			(end 3.700018 1.549908)
			(stroke
				(width 0.1524)
				(type default)
			)
			(layer "F.SilkS")
		)
		(fp_line
			(start 1.75006 4.549902)
			(end 1.75006 1.549908)
			(stroke
				(width 0.1524)
				(type default)
			)
			(layer "F.SilkS")
		)
		(fp_line
			(start 3.700018 -4.549902)
			(end 3.1496 -4.549902)
			(stroke
				(width 0.1524)
				(type default)
			)
			(layer "F.SilkS")
		)
		(fp_line
			(start 3.700018 -2.51206)
			(end 3.700018 -4.549902)
			(stroke
				(width 0.1524)
				(type default)
			)
			(layer "F.SilkS")
		)
		(fp_line
			(start 3.700018 -0.88646)
			(end 3.700018 -0.98806)
			(stroke
				(width 0.1524)
				(type default)
			)
			(layer "F.SilkS")
		)
		(fp_line
			(start 3.700018 1.549908)
			(end 3.700018 1.39954)
			(stroke
				(width 0.1524)
				(type default)
			)
			(layer "F.SilkS")
		)
		(fp_poly
			(pts
				(xy -3.883914 -4.043934) (xy -5.310886 -3.330448) (xy -5.310886 -4.75742)
			)
			(stroke
				(width 0)
				(type default)
			)
			(fill yes)
			(layer "F.SilkS")
		)
		(fp_line
			(start -3.700018 -4.549902)
			(end -3.700018 1.549908)
			(stroke
				(width 0.1)
				(type default)
			)
			(layer "F.Fab")
		)
		(fp_line
			(start -3.700018 1.549908)
			(end -1.75006 1.549908)
			(stroke
				(width 0.1)
				(type default)
			)
			(layer "F.Fab")
		)
		(fp_line
			(start -1.75006 1.549908)
			(end -1.75006 4.549902)
			(stroke
				(width 0.1)
				(type default)
			)
			(layer "F.Fab")
		)
		(fp_line
			(start -1.75006 4.549902)
			(end 1.75006 4.549902)
			(stroke
				(width 0.1)
				(type default)
			)
			(layer "F.Fab")
		)
		(fp_line
			(start 1.75006 1.549908)
			(end 3.700018 1.549908)
			(stroke
				(width 0.1)
				(type default)
			)
			(layer "F.Fab")
		)
		(fp_line
			(start 1.75006 4.549902)
			(end 1.75006 1.549908)
			(stroke
				(width 0.1)
				(type default)
			)
			(layer "F.Fab")
		)
		(fp_line
			(start 3.700018 -4.549902)
			(end -3.700018 -4.549902)
			(stroke
				(width 0.1)
				(type default)
			)
			(layer "F.Fab")
		)
		(fp_line
			(start 3.700018 1.549908)
			(end 3.700018 -4.549902)
			(stroke
				(width 0.1)
				(type default)
			)
			(layer "F.Fab")
		)
		(fp_poly
			(pts
				(xy -3.883914 -4.043934) (xy -5.310886 -3.330448) (xy -5.310886 -4.75742)
			)
			(stroke
				(width 0)
				(type default)
			)
			(fill yes)
			(layer "F.Fab")
		)
		(pad "" np_thru_hole circle
			(at -3.50012 -1.75006)
			(size 0.9144 0.9144)
			(drill 0.9144)
			(layers "*.Cu" "*.Mask")
			(clearance 0.381)
			(thermal_gap 0.381)
		)
		(pad "" np_thru_hole circle
			(at 3.50012 -1.75006)
			(size 0.9144 0.9144)
			(drill 0.9144)
			(layers "*.Cu" "*.Mask")
			(clearance 0.381)
			(thermal_gap 0.381)
		)
		(pad "1" smd rect
			(at -2.249932 -4.05003)
			(size 1.4986 2.0066)
			(layers "F.Cu" "F.Mask" "F.Paste")
			(net "GND")
		)
		(pad "2" smd rect
			(at 2.249932 -4.05003)
			(size 1.4986 2.0066)
			(layers "F.Cu" "F.Mask" "F.Paste")
			(net "REAR_ID_RST_BTN_N")
		)
		(pad "3" smd rect
			(at -4.19989 0.249936)
			(size 2.0066 2.0066)
			(layers "F.Cu" "F.Mask" "F.Paste")
			(net "GND")
		)
		(pad "4" smd rect
			(at 4.19989 0.249936)
			(size 2.0066 2.0066)
			(layers "F.Cu" "F.Mask" "F.Paste")
			(net "GND")
		)
		(zone
			(layers "F.Cu" "B.Cu" "In1.Cu" "In2.Cu" "In3.Cu" "In4.Cu" "In5.Cu" "In6.Cu"
				"In7.Cu" "In8.Cu" "In9.Cu" "In10.Cu"
			)
			(hatch none 0.5)
			(connect_pads
				(clearance 0)
			)
			(min_thickness 0.25)
			(keepout
				(tracks not_allowed)
				(vias allowed)
				(pads allowed)
				(copperpour not_allowed)
				(footprints allowed)
			)
			(placement
				(enabled no)
				(sheetname "")
			)
			(fill
				(thermal_gap 0.5)
				(thermal_bridge_width 0.5)
				(island_removal_mode 0)
			)
			(polygon
				(pts
					(arc
						(start 79.363824 -4.69011)
						(mid 77.636116 -4.69011)
						(end 79.363824 -4.69011)
					)
				)
			)
		)
		(zone
			(layers "F.Cu" "B.Cu" "In1.Cu" "In2.Cu" "In3.Cu" "In4.Cu" "In5.Cu" "In6.Cu"
				"In7.Cu" "In8.Cu" "In9.Cu" "In10.Cu"
			)
			(hatch none 0.5)
			(connect_pads
				(clearance 0)
			)
			(min_thickness 0.25)
			(keepout
				(tracks not_allowed)
				(vias allowed)
				(pads allowed)
				(copperpour not_allowed)
				(footprints allowed)
			)
			(placement
				(enabled no)
				(sheetname "")
			)
			(fill
				(thermal_gap 0.5)
				(thermal_bridge_width 0.5)
				(island_removal_mode 0)
			)
			(polygon
				(pts
					(arc
						(start 86.36381 -4.69011)
						(mid 84.63661 -4.69011)
						(end 86.36381 -4.69011)
					)
				)
			)
		)
	)
)
